(kicad_pcb
	(version 20260206)
	(generator "pcbnew")
	(generator_version "10.0")
	(general
		(thickness 1.6)
		(legacy_teardrops no)
	)
	(paper "A4")
	(title_block
		(title "v1-pdb — T6M_PDB_D_0927_0900.brd")
		(comment 1 "Open CloudServer (Microsoft) / footprint 312 of 321 (J13), pads 1-46 of 46")
	)
	(layers
		(0 "F.Cu" signal "TOP")
		(4 "In1.Cu" signal "GND")
		(6 "In2.Cu" signal "IN1")
		(8 "In3.Cu" signal "VCC")
		(10 "In4.Cu" signal "VCC1")
		(12 "In5.Cu" signal "IN2")
		(14 "In6.Cu" signal "GND1")
		(2 "B.Cu" signal "BOTTOM")
		(9 "F.Adhes" user "F.Adhesive")
		(11 "B.Adhes" user "B.Adhesive")
		(13 "F.Paste" user "Package Geometry/Pastemask Top")
		(15 "B.Paste" user "Package Geometry/Pastemask Bottom")
		(5 "F.SilkS" user "Ref Des/Silkscreen Top")
		(7 "B.SilkS" user "Ref Des/Silkscreen Bottom")
		(1 "F.Mask" user "Board Geometry/Soldermask Top")
		(3 "B.Mask" user "Board Geometry/Soldermask Bottom")
		(17 "Dwgs.User" user "User.Drawings")
		(19 "Cmts.User" user "User.Comments")
		(21 "Eco1.User" user "User.Eco1")
		(23 "Eco2.User" user "User.Eco2")
		(25 "Edge.Cuts" user "Board Geometry/Outline")
		(27 "Margin" user)
		(31 "F.CrtYd" user "Package Geometry/Place Bound Top")
		(29 "B.CrtYd" user "Package Geometry/Place Bound Bottom")
		(35 "F.Fab" user "Ref Des/Assembly Top")
		(33 "B.Fab" user "Ref Des/Assembly Bottom")
	)
	(footprint ""
		(layer "B.Cu")
		(at 44.03979 -274.96008 90)
		(property "Reference" "J13"
			(at 6.540246 -4.559808 0)
			(unlocked yes)
			(layer "B.SilkS")
			(effects
				(font
					(size 0.7874 0.5842)
					(thickness 0.1524)
				)
				(justify left mirror)
			)
		)
		(property "Value" ""
			(at 0 0 90)
			(layer "B.Fab")
			(effects
				(font
					(size 1.27 1.27)
				)
				(justify mirror)
			)
		)
		(duplicate_pad_numbers_are_jumpers no)
		(pad "" np_thru_hole circle
			(at -1.35001 -2.54)
			(size 2.5146 2.5146)
			(drill 2.5146)
			(layers "*.Cu" "*.Mask")
			(clearance 0.381)
			(thermal_gap 0.381)
		)
		(pad "" np_thru_hole circle
			(at 0 50.8)
			(size 2.5146 2.5146)
			(drill 2.5146)
			(layers "*.Cu" "*.Mask")
			(clearance 0.381)
			(thermal_gap 0.381)
		)
		(pad "P1" thru_hole rect
			(at 0 0)
			(size 1.1684 1.1684)
			(drill 0.762)
			(layers "*.Cu" "*.Mask")
			(remove_unused_layers no)
			(net "GND")
			(clearance 0.0508)
			(padstack
				(mode front_inner_back)
				(layer "Inner"
					(shape circle)
					(size 1.1684 1.1684)
					(clearance 0.0508)
				)
				(layer "B.Cu"
					(shape rect)
					(size 1.1684 1.1684)
					(thermal_gap 0.0508)
					(clearance 0.0508)
				)
			)
		)
		(pad "P2" thru_hole circle
			(at 0 2.54)
			(size 1.1684 1.1684)
			(drill 0.762)
			(layers "*.Cu" "*.Mask")
			(remove_unused_layers no)
			(net "GND")
			(clearance 0.0508)
			(thermal_gap 0.0508)
		)
		(pad "P3" thru_hole circle
			(at 0 5.08)
			(size 1.1684 1.1684)
			(drill 0.762)
			(layers "*.Cu" "*.Mask")
			(remove_unused_layers no)
			(net "GND")
			(clearance 0.0508)
			(thermal_gap 0.0508)
		)
		(pad "P4" thru_hole circle
			(at 0 7.62)
			(size 1.1684 1.1684)
			(drill 0.762)
			(layers "*.Cu" "*.Mask")
			(remove_unused_layers no)
			(net "GND")
			(clearance 0.0508)
			(thermal_gap 0.0508)
		)
		(pad "P5" thru_hole circle
			(at 0 10.16)
			(size 1.1684 1.1684)
			(drill 0.762)
			(layers "*.Cu" "*.Mask")
			(remove_unused_layers no)
			(net "GND")
			(clearance 0.0508)
			(thermal_gap 0.0508)
		)
		(pad "P6" thru_hole circle
			(at 0 12.7)
			(size 1.1684 1.1684)
			(drill 0.762)
			(layers "*.Cu" "*.Mask")
			(remove_unused_layers no)
			(net "GND")
			(clearance 0.0508)
			(thermal_gap 0.0508)
		)
		(pad "P7" thru_hole circle
			(at 0 15.24)
			(size 1.1684 1.1684)
			(drill 0.762)
			(layers "*.Cu" "*.Mask")
			(remove_unused_layers no)
			(net "GND")
			(clearance 0.0508)
			(thermal_gap 0.0508)
		)
		(pad "P8" thru_hole circle
			(at 0 17.78)
			(size 1.1684 1.1684)
			(drill 0.762)
			(layers "*.Cu" "*.Mask")
			(remove_unused_layers no)
			(net "GND")
			(clearance 0.0508)
			(thermal_gap 0.0508)
		)
		(pad "P9" thru_hole circle
			(at 0 20.32)
			(size 1.1684 1.1684)
			(drill 0.762)
			(layers "*.Cu" "*.Mask")
			(remove_unused_layers no)
			(net "P12V")
			(clearance 0.0508)
			(thermal_gap 0.0508)
		)
		(pad "P10" thru_hole circle
			(at 0 22.86)
			(size 1.1684 1.1684)
			(drill 0.762)
			(layers "*.Cu" "*.Mask")
			(remove_unused_layers no)
			(net "P12V")
			(clearance 0.0508)
			(thermal_gap 0.0508)
		)
		(pad "P11" thru_hole circle
			(at 0 25.4)
			(size 1.1684 1.1684)
			(drill 0.762)
			(layers "*.Cu" "*.Mask")
			(remove_unused_layers no)
			(net "P12V")
			(clearance 0.0508)
			(thermal_gap 0.0508)
		)
		(pad "P12" thru_hole circle
			(at 0 27.94)
			(size 1.1684 1.1684)
			(drill 0.762)
			(layers "*.Cu" "*.Mask")
			(remove_unused_layers no)
			(net "P12V")
			(clearance 0.0508)
			(thermal_gap 0.0508)
		)
		(pad "P13" thru_hole circle
			(at 0 30.48)
			(size 1.1684 1.1684)
			(drill 0.762)
			(layers "*.Cu" "*.Mask")
			(remove_unused_layers no)
			(net "P12V")
			(clearance 0.0508)
			(thermal_gap 0.0508)
		)
		(pad "P14" thru_hole circle
			(at 0 33.02)
			(size 1.1684 1.1684)
			(drill 0.762)
			(layers "*.Cu" "*.Mask")
			(remove_unused_layers no)
			(net "P12V")
			(clearance 0.0508)
			(thermal_gap 0.0508)
		)
		(pad "P15" thru_hole circle
			(at 0 35.56)
			(size 1.1684 1.1684)
			(drill 0.762)
			(layers "*.Cu" "*.Mask")
			(remove_unused_layers no)
			(net "P12V")
			(clearance 0.0508)
			(thermal_gap 0.0508)
		)
		(pad "P16" thru_hole circle
			(at 0 38.1)
			(size 1.1684 1.1684)
			(drill 0.762)
			(layers "*.Cu" "*.Mask")
			(remove_unused_layers no)
			(net "P12V")
			(clearance 0.0508)
			(thermal_gap 0.0508)
		)
		(pad "P17" thru_hole circle
			(at -2.70002 38.1)
			(size 1.1684 1.1684)
			(drill 0.762)
			(layers "*.Cu" "*.Mask")
			(remove_unused_layers no)
			(net "P12V")
			(clearance 0.0508)
			(thermal_gap 0.0508)
		)
		(pad "P18" thru_hole circle
			(at -2.70002 35.56)
			(size 1.1684 1.1684)
			(drill 0.762)
			(layers "*.Cu" "*.Mask")
			(remove_unused_layers no)
			(net "P12V")
			(clearance 0.0508)
			(thermal_gap 0.0508)
		)
		(pad "P19" thru_hole circle
			(at -2.70002 33.02)
			(size 1.1684 1.1684)
			(drill 0.762)
			(layers "*.Cu" "*.Mask")
			(remove_unused_layers no)
			(net "P12V")
			(clearance 0.0508)
			(thermal_gap 0.0508)
		)
		(pad "P20" thru_hole circle
			(at -2.70002 30.48)
			(size 1.1684 1.1684)
			(drill 0.762)
			(layers "*.Cu" "*.Mask")
			(remove_unused_layers no)
			(net "P12V")
			(clearance 0.0508)
			(thermal_gap 0.0508)
		)
		(pad "P21" thru_hole circle
			(at -2.70002 27.94)
			(size 1.1684 1.1684)
			(drill 0.762)
			(layers "*.Cu" "*.Mask")
			(remove_unused_layers no)
			(net "P12V")
			(clearance 0.0508)
			(thermal_gap 0.0508)
		)
		(pad "P22" thru_hole circle
			(at -2.70002 25.4)
			(size 1.1684 1.1684)
			(drill 0.762)
			(layers "*.Cu" "*.Mask")
			(remove_unused_layers no)
			(net "P12V")
			(clearance 0.0508)
			(thermal_gap 0.0508)
		)
		(pad "P23" thru_hole circle
			(at -2.70002 22.86)
			(size 1.1684 1.1684)
			(drill 0.762)
			(layers "*.Cu" "*.Mask")
			(remove_unused_layers no)
			(net "P12V")
			(clearance 0.0508)
			(thermal_gap 0.0508)
		)
		(pad "P24" thru_hole circle
			(at -2.70002 20.32)
			(size 1.1684 1.1684)
			(drill 0.762)
			(layers "*.Cu" "*.Mask")
			(remove_unused_layers no)
			(net "P12V")
			(clearance 0.0508)
			(thermal_gap 0.0508)
		)
		(pad "P25" thru_hole circle
			(at -2.70002 17.78)
			(size 1.1684 1.1684)
			(drill 0.762)
			(layers "*.Cu" "*.Mask")
			(remove_unused_layers no)
			(net "GND")
			(clearance 0.0508)
			(thermal_gap 0.0508)
		)
		(pad "P26" thru_hole circle
			(at -2.70002 15.24)
			(size 1.1684 1.1684)
			(drill 0.762)
			(layers "*.Cu" "*.Mask")
			(remove_unused_layers no)
			(net "GND")
			(clearance 0.0508)
			(thermal_gap 0.0508)
		)
		(pad "P27" thru_hole circle
			(at -2.70002 12.7)
			(size 1.1684 1.1684)
			(drill 0.762)
			(layers "*.Cu" "*.Mask")
			(remove_unused_layers no)
			(net "GND")
			(clearance 0.0508)
			(thermal_gap 0.0508)
		)
		(pad "P28" thru_hole circle
			(at -2.70002 10.16)
			(size 1.1684 1.1684)
			(drill 0.762)
			(layers "*.Cu" "*.Mask")
			(remove_unused_layers no)
			(net "GND")
			(clearance 0.0508)
			(thermal_gap 0.0508)
		)
		(pad "P29" thru_hole circle
			(at -2.70002 7.62)
			(size 1.1684 1.1684)
			(drill 0.762)
			(layers "*.Cu" "*.Mask")
			(remove_unused_layers no)
			(net "GND")
			(clearance 0.0508)
			(thermal_gap 0.0508)
		)
		(pad "P30" thru_hole circle
			(at -2.70002 5.08)
			(size 1.1684 1.1684)
			(drill 0.762)
			(layers "*.Cu" "*.Mask")
			(remove_unused_layers no)
			(net "GND")
			(clearance 0.0508)
			(thermal_gap 0.0508)
		)
		(pad "P31" thru_hole circle
			(at -2.70002 2.54)
			(size 1.1684 1.1684)
			(drill 0.762)
			(layers "*.Cu" "*.Mask")
			(remove_unused_layers no)
			(net "GND")
			(clearance 0.0508)
			(thermal_gap 0.0508)
		)
		(pad "P32" thru_hole circle
			(at -2.70002 0)
			(size 1.1684 1.1684)
			(drill 0.762)
			(layers "*.Cu" "*.Mask")
			(remove_unused_layers no)
			(net "GND")
			(clearance 0.0508)
			(thermal_gap 0.0508)
		)
		(pad "S1" thru_hole circle
			(at 0.55499 41.60012)
			(size 1.1684 1.1684)
			(drill 0.762)
			(layers "*.Cu" "*.Mask")
			(remove_unused_layers no)
			(net "T7_BLAD1_TXD")
			(clearance 0.0508)
			(thermal_gap 0.0508)
		)
		(pad "S2" thru_hole circle
			(at -0.71501 42.87012)
			(size 1.1684 1.1684)
			(drill 0.762)
			(layers "*.Cu" "*.Mask")
			(remove_unused_layers no)
			(net "T7_BLAD1_RXD")
			(clearance 0.0508)
			(thermal_gap 0.0508)
		)
		(pad "S3" thru_hole circle
			(at 0.55499 44.14012)
			(size 1.1684 1.1684)
			(drill 0.762)
			(layers "*.Cu" "*.Mask")
			(remove_unused_layers no)
			(net "T7_BLAD1_EN")
			(clearance 0.0508)
			(thermal_gap 0.0508)
		)
		(pad "S4" thru_hole circle
			(at -0.71501 45.41012)
			(size 1.1684 1.1684)
			(drill 0.762)
			(layers "*.Cu" "*.Mask")
			(remove_unused_layers no)
			(net "T7_BLAD2_EN")
			(clearance 0.0508)
			(thermal_gap 0.0508)
		)
		(pad "S5" thru_hole circle
			(at 0.55499 46.68012)
			(size 1.1684 1.1684)
			(drill 0.762)
			(layers "*.Cu" "*.Mask")
			(remove_unused_layers no)
			(net "T7_BLAD2_TXD")
			(clearance 0.0508)
			(thermal_gap 0.0508)
		)
		(pad "S6" thru_hole circle
			(at -0.71501 47.95012)
			(size 1.1684 1.1684)
			(drill 0.762)
			(layers "*.Cu" "*.Mask")
			(remove_unused_layers no)
			(net "T7_BLAD2_RXD")
			(clearance 0.0508)
			(thermal_gap 0.0508)
		)
		(pad "S7" thru_hole circle
			(at -3.25501 47.95012)
			(size 1.1684 1.1684)
			(drill 0.762)
			(layers "*.Cu" "*.Mask")
			(remove_unused_layers no)
			(net "T7_BLAD4_RXD")
			(clearance 0.0508)
			(thermal_gap 0.0508)
		)
		(pad "S8" thru_hole circle
			(at -1.98501 46.68012)
			(size 1.1684 1.1684)
			(drill 0.762)
			(layers "*.Cu" "*.Mask")
			(remove_unused_layers no)
			(net "T7_BLAD4_TXD")
			(clearance 0.0508)
			(thermal_gap 0.0508)
		)
		(pad "S9" thru_hole circle
			(at -3.25501 45.41012)
			(size 1.1684 1.1684)
			(drill 0.762)
			(layers "*.Cu" "*.Mask")
			(remove_unused_layers no)
			(net "T7_BLAD4_EN")
			(clearance 0.0508)
			(thermal_gap 0.0508)
		)
		(pad "S10" thru_hole circle
			(at -1.98501 44.14012)
			(size 1.1684 1.1684)
			(drill 0.762)
			(layers "*.Cu" "*.Mask")
			(remove_unused_layers no)
			(net "T7_BLAD3_EN")
			(clearance 0.0508)
			(thermal_gap 0.0508)
		)
		(pad "S11" thru_hole circle
			(at -3.25501 42.87012)
			(size 1.1684 1.1684)
			(drill 0.762)
			(layers "*.Cu" "*.Mask")
			(remove_unused_layers no)
			(net "T7_BLAD3_RXD")
			(clearance 0.0508)
			(thermal_gap 0.0508)
		)
		(pad "S12" thru_hole circle
			(at -1.98501 41.60012)
			(size 1.1684 1.1684)
			(drill 0.762)
			(layers "*.Cu" "*.Mask")
			(remove_unused_layers no)
			(net "T7_BLAD3_TXD")
			(clearance 0.0508)
			(thermal_gap 0.0508)
		)
	)
)
